# T6G (Grand Teton) — schematic netlist excerpt (pin names and nets, part order shuffled) for the footprints in the layout excerpt that follows; sources: Cadence DE-HDL packaged netlist, KiCad conversion of 04192023_DAF0TMB3IC0_F0TG_MB_C_brd_V02_OCP.brd

R158  Q_RES  33 5% CHIP  pkg 0402LF  page 81 : A = FM_PLD_CPU0_PRSNT_HDT ; B = CPU0_HDT_BYPASS_SEL
R1385  Q_RES  2K 1% EMPTY  pkg 0402LF  page 151 : A = SMB_CPU0_CPU1_SEC_SDA ; B = P3V3_AUX

(kicad_pcb
	(version 20260206)
	(generator "pcbnew")
	(generator_version "10.0")
	(general
		(thickness 1.6)
		(legacy_teardrops no)
	)
	(paper "A4")
	(title_block
		(title "04192023_DAF0TMB3IC0_F0TG_MB_C_brd_V02_OCP.brd")
		(comment 1 "Grand Teton / footprints 7957-7958 of 8354")
	)
	(layers
		(0 "F.Cu" signal "TOP")
		(4 "In1.Cu" signal "GND")
		(6 "In2.Cu" signal "IN1")
		(8 "In3.Cu" signal "GND1")
		(10 "In4.Cu" signal "IN2")
		(12 "In5.Cu" signal "GND2")
		(14 "In6.Cu" signal "IN3")
		(16 "In7.Cu" signal "GND3")
		(18 "In8.Cu" signal "VCC")
		(20 "In9.Cu" signal "VCC1")
		(22 "In10.Cu" signal "GND4")
		(24 "In11.Cu" signal "IN4")
		(26 "In12.Cu" signal "GND5")
		(28 "In13.Cu" signal "IN5")
		(30 "In14.Cu" signal "GND6")
		(32 "In15.Cu" signal "IN6")
		(34 "In16.Cu" signal "GND7")
		(2 "B.Cu" signal "BOTTOM")
		(9 "F.Adhes" user "F.Adhesive")
		(11 "B.Adhes" user "B.Adhesive")
		(13 "F.Paste" user "Package Geometry/Pastemask Top")
		(15 "B.Paste" user "Package Geometry/Pastemask Bottom")
		(5 "F.SilkS" user "Ref Des/Silkscreen Top")
		(7 "B.SilkS" user "Ref Des/Silkscreen Bottom")
		(1 "F.Mask" user "Board Geometry/Soldermask Top")
		(3 "B.Mask" user "Board Geometry/Soldermask Bottom")
		(17 "Dwgs.User" user "User.Drawings")
		(19 "Cmts.User" user "User.Comments")
		(21 "Eco1.User" user "User.Eco1")
		(23 "Eco2.User" user "User.Eco2")
		(25 "Edge.Cuts" user "Board Geometry/Outline")
		(27 "Margin" user)
		(31 "F.CrtYd" user "Package Geometry/Place Bound Top")
		(29 "B.CrtYd" user "Package Geometry/Place Bound Bottom")
		(35 "F.Fab" user "Ref Des/Assembly Top")
		(33 "B.Fab" user "Ref Des/Assembly Bottom")
	)
	(footprint ""
		(layer "B.Cu")
		(at 192.189608 -126.833376 -90)
		(property "Reference" "R158"
			(at 0 0 90)
			(layer "B.SilkS")
			(hide yes)
			(effects
				(font
					(size 1.27 1.27)
				)
				(justify mirror)
			)
		)
		(property "Value" ""
			(at 0 0 90)
			(layer "B.Fab")
			(effects
				(font
					(size 1.27 1.27)
				)
				(justify mirror)
			)
		)
		(duplicate_pad_numbers_are_jumpers no)
		(fp_line
			(start -0.7874 0.4064)
			(end 0.7874 0.4064)
			(stroke
				(width 0.1524)
				(type default)
			)
			(layer "B.SilkS")
		)
		(fp_line
			(start 0.7874 0.4064)
			(end 0.7874 -0.4064)
			(stroke
				(width 0.1524)
				(type default)
			)
			(layer "B.SilkS")
		)
		(fp_line
			(start -0.7874 -0.4064)
			(end -0.7874 0.4064)
			(stroke
				(width 0.1524)
				(type default)
			)
			(layer "B.SilkS")
		)
		(fp_line
			(start 0.7874 -0.4064)
			(end -0.7874 -0.4064)
			(stroke
				(width 0.1524)
				(type default)
			)
			(layer "B.SilkS")
		)
		(fp_line
			(start -0.67945 0.3048)
			(end -0.120396 0.3048)
			(stroke
				(width 0.1)
				(type default)
			)
			(layer "B.Fab")
		)
		(fp_line
			(start -0.120396 0.3048)
			(end -0.120396 0.2794)
			(stroke
				(width 0.1)
				(type default)
			)
			(layer "B.Fab")
		)
		(fp_line
			(start 0.12065 0.3048)
			(end 0.67945 0.3048)
			(stroke
				(width 0.1)
				(type default)
			)
			(layer "B.Fab")
		)
		(fp_line
			(start 0.67945 0.3048)
			(end 0.67945 -0.305054)
			(stroke
				(width 0.1)
				(type default)
			)
			(layer "B.Fab")
		)
		(fp_line
			(start -0.120396 0.2794)
			(end 0.12065 0.2794)
			(stroke
				(width 0.1)
				(type default)
			)
			(layer "B.Fab")
		)
		(fp_line
			(start 0.12065 0.2794)
			(end 0.12065 0.3048)
			(stroke
				(width 0.1)
				(type default)
			)
			(layer "B.Fab")
		)
		(fp_line
			(start -0.12065 -0.2794)
			(end -0.12065 -0.3048)
			(stroke
				(width 0.1)
				(type default)
			)
			(layer "B.Fab")
		)
		(fp_line
			(start 0.12065 -0.2794)
			(end -0.12065 -0.2794)
			(stroke
				(width 0.1)
				(type default)
			)
			(layer "B.Fab")
		)
		(fp_line
			(start -0.67945 -0.3048)
			(end -0.67945 0.3048)
			(stroke
				(width 0.1)
				(type default)
			)
			(layer "B.Fab")
		)
		(fp_line
			(start -0.12065 -0.3048)
			(end -0.67945 -0.3048)
			(stroke
				(width 0.1)
				(type default)
			)
			(layer "B.Fab")
		)
		(fp_line
			(start 0.12065 -0.305054)
			(end 0.12065 -0.2794)
			(stroke
				(width 0.1)
				(type default)
			)
			(layer "B.Fab")
		)
		(fp_line
			(start 0.67945 -0.305054)
			(end 0.12065 -0.305054)
			(stroke
				(width 0.1)
				(type default)
			)
			(layer "B.Fab")
		)
		(pad "1" smd circle
			(at 0.40005 0 90)
			(size 0 0)
			(layers "B.Cu" "B.Mask" "B.Paste")
			(net "FM_PLD_CPU0_PRSNT_HDT")
		)
		(pad "2" smd circle
			(at -0.40005 0 90)
			(size 0 0)
			(layers "B.Cu" "B.Mask" "B.Paste")
			(net "CPU0_HDT_BYPASS_SEL")
		)
	)
	(footprint ""
		(layer "B.Cu")
		(at 175.333914 -14.308328 90)
		(property "Reference" "R1385"
			(at 0 0 90)
			(layer "B.SilkS")
			(hide yes)
			(effects
				(font
					(size 1.27 1.27)
				)
				(justify mirror)
			)
		)
		(property "Value" ""
			(at 0 0 90)
			(layer "B.Fab")
			(effects
				(font
					(size 1.27 1.27)
				)
				(justify mirror)
			)
		)
		(duplicate_pad_numbers_are_jumpers no)
		(fp_line
			(start 0.7874 -0.4064)
			(end -0.7874 -0.4064)
			(stroke
				(width 0.1524)
				(type default)
			)
			(layer "B.SilkS")
		)
		(fp_line
			(start -0.7874 -0.4064)
			(end -0.7874 0.4064)
			(stroke
				(width 0.1524)
				(type default)
			)
			(layer "B.SilkS")
		)
		(fp_line
			(start 0.7874 0.4064)
			(end 0.7874 -0.4064)
			(stroke
				(width 0.1524)
				(type default)
			)
			(layer "B.SilkS")
		)
		(fp_line
			(start -0.7874 0.4064)
			(end 0.7874 0.4064)
			(stroke
				(width 0.1524)
				(type default)
			)
			(layer "B.SilkS")
		)
		(fp_line
			(start 0.67945 -0.305054)
			(end 0.12065 -0.305054)
			(stroke
				(width 0.1)
				(type default)
			)
			(layer "B.Fab")
		)
		(fp_line
			(start 0.12065 -0.305054)
			(end 0.12065 -0.2794)
			(stroke
				(width 0.1)
				(type default)
			)
			(layer "B.Fab")
		)
		(fp_line
			(start -0.12065 -0.3048)
			(end -0.67945 -0.3048)
			(stroke
				(width 0.1)
				(type default)
			)
			(layer "B.Fab")
		)
		(fp_line
			(start -0.67945 -0.3048)
			(end -0.67945 0.3048)
			(stroke
				(width 0.1)
				(type default)
			)
			(layer "B.Fab")
		)
		(fp_line
			(start 0.12065 -0.2794)
			(end -0.12065 -0.2794)
			(stroke
				(width 0.1)
				(type default)
			)
			(layer "B.Fab")
		)
		(fp_line
			(start -0.12065 -0.2794)
			(end -0.12065 -0.3048)
			(stroke
				(width 0.1)
				(type default)
			)
			(layer "B.Fab")
		)
		(fp_line
			(start 0.12065 0.2794)
			(end 0.12065 0.3048)
			(stroke
				(width 0.1)
				(type default)
			)
			(layer "B.Fab")
		)
		(fp_line
			(start -0.120396 0.2794)
			(end 0.12065 0.2794)
			(stroke
				(width 0.1)
				(type default)
			)
			(layer "B.Fab")
		)
		(fp_line
			(start 0.67945 0.3048)
			(end 0.67945 -0.305054)
			(stroke
				(width 0.1)
				(type default)
			)
			(layer "B.Fab")
		)
		(fp_line
			(start 0.12065 0.3048)
			(end 0.67945 0.3048)
			(stroke
				(width 0.1)
				(type default)
			)
			(layer "B.Fab")
		)
		(fp_line
			(start -0.120396 0.3048)
			(end -0.120396 0.2794)
			(stroke
				(width 0.1)
				(type default)
			)
			(layer "B.Fab")
		)
		(fp_line
			(start -0.67945 0.3048)
			(end -0.120396 0.3048)
			(stroke
				(width 0.1)
				(type default)
			)
			(layer "B.Fab")
		)
		(pad "1" smd circle
			(at 0.40005 0 270)
			(size 0 0)
			(layers "B.Cu" "B.Mask" "B.Paste")
			(net "SMB_CPU0_CPU1_SEC_SDA")
		)
		(pad "2" smd circle
			(at -0.40005 0 270)
			(size 0 0)
			(layers "B.Cu" "B.Mask" "B.Paste")
			(net "P3V3_AUX")
		)
	)
)
